# S9S_MB_2U (Grand Teton) — schematic netlist excerpt (pin names and nets, part order shuffled) for the footprints in the layout excerpt that follows; sources: Cadence DE-HDL packaged netlist, KiCad conversion of 03242023_DA0F0TMBIJ0_F0T_Motherboard_J_brd_V01_OCP.brd

R1494  Q_RES  1K 1% EMPTY  pkg 0402LF  page 220 : A = FM_DIS_PS_PWROK_DLY ; B = GND

(kicad_pcb
	(version 20260206)
	(generator "pcbnew")
	(generator_version "10.0")
	(general
		(thickness 1.6)
		(legacy_teardrops no)
	)
	(paper "A4")
	(title_block
		(title "03242023_DA0F0TMBIJ0_F0T_Motherboard_J_brd_V01_OCP.brd")
		(comment 1 "Grand Teton / footprints 3585-3585 of 6105")
	)
	(layers
		(0 "F.Cu" signal "TOP")
		(4 "In1.Cu" signal "GND")
		(6 "In2.Cu" signal "IN1")
		(8 "In3.Cu" signal "GND1")
		(10 "In4.Cu" signal "IN2")
		(12 "In5.Cu" signal "GND2")
		(14 "In6.Cu" signal "IN3")
		(16 "In7.Cu" signal "GND3")
		(18 "In8.Cu" signal "VCC")
		(20 "In9.Cu" signal "VCC1")
		(22 "In10.Cu" signal "GND4")
		(24 "In11.Cu" signal "IN4")
		(26 "In12.Cu" signal "GND5")
		(28 "In13.Cu" signal "IN5")
		(30 "In14.Cu" signal "GND6")
		(32 "In15.Cu" signal "IN6")
		(34 "In16.Cu" signal "GND7")
		(2 "B.Cu" signal "BOTTOM")
		(9 "F.Adhes" user "F.Adhesive")
		(11 "B.Adhes" user "B.Adhesive")
		(13 "F.Paste" user "Package Geometry/Pastemask Top")
		(15 "B.Paste" user "Package Geometry/Pastemask Bottom")
		(5 "F.SilkS" user "Ref Des/Silkscreen Top")
		(7 "B.SilkS" user "Ref Des/Silkscreen Bottom")
		(1 "F.Mask" user "Board Geometry/Soldermask Top")
		(3 "B.Mask" user "Board Geometry/Soldermask Bottom")
		(17 "Dwgs.User" user "User.Drawings")
		(19 "Cmts.User" user "User.Comments")
		(21 "Eco1.User" user "User.Eco1")
		(23 "Eco2.User" user "User.Eco2")
		(25 "Edge.Cuts" user "Board Geometry/Outline")
		(27 "Margin" user)
		(31 "F.CrtYd" user "Package Geometry/Place Bound Top")
		(29 "B.CrtYd" user "Package Geometry/Place Bound Bottom")
		(35 "F.Fab" user "Ref Des/Assembly Top")
		(33 "B.Fab" user "Ref Des/Assembly Bottom")
	)
	(footprint ""
		(layer "F.Cu")
		(at 193.60388 -106.225848)
		(property "Reference" "R1494"
			(at 0 0 0)
			(layer "F.SilkS")
			(hide yes)
			(effects
				(font
					(size 1.27 1.27)
				)
			)
		)
		(property "Value" ""
			(at 0 0 0)
			(layer "F.Fab")
			(effects
				(font
					(size 1.27 1.27)
				)
			)
		)
		(duplicate_pad_numbers_are_jumpers no)
		(fp_line
			(start -0.7874 -0.4064)
			(end 0.7874 -0.4064)
			(stroke
				(width 0.1524)
				(type default)
			)
			(layer "F.SilkS")
		)
		(fp_line
			(start -0.7874 0.4064)
			(end -0.7874 -0.4064)
			(stroke
				(width 0.1524)
				(type default)
			)
			(layer "F.SilkS")
		)
		(fp_line
			(start 0.7874 -0.4064)
			(end 0.7874 0.4064)
			(stroke
				(width 0.1524)
				(type default)
			)
			(layer "F.SilkS")
		)
		(fp_line
			(start 0.7874 0.4064)
			(end -0.7874 0.4064)
			(stroke
				(width 0.1524)
				(type default)
			)
			(layer "F.SilkS")
		)
		(fp_line
			(start -0.67945 -0.305054)
			(end -0.12065 -0.305054)
			(stroke
				(width 0.1)
				(type default)
			)
			(layer "F.Fab")
		)
		(fp_line
			(start -0.67945 0.3048)
			(end -0.67945 -0.305054)
			(stroke
				(width 0.1)
				(type default)
			)
			(layer "F.Fab")
		)
		(fp_line
			(start -0.12065 -0.305054)
			(end -0.12065 -0.2794)
			(stroke
				(width 0.1)
				(type default)
			)
			(layer "F.Fab")
		)
		(fp_line
			(start -0.12065 -0.2794)
			(end 0.12065 -0.2794)
			(stroke
				(width 0.1)
				(type default)
			)
			(layer "F.Fab")
		)
		(fp_line
			(start -0.12065 0.2794)
			(end -0.12065 0.3048)
			(stroke
				(width 0.1)
				(type default)
			)
			(layer "F.Fab")
		)
		(fp_line
			(start -0.12065 0.3048)
			(end -0.67945 0.3048)
			(stroke
				(width 0.1)
				(type default)
			)
			(layer "F.Fab")
		)
		(fp_line
			(start 0.120396 0.2794)
			(end -0.12065 0.2794)
			(stroke
				(width 0.1)
				(type default)
			)
			(layer "F.Fab")
		)
		(fp_line
			(start 0.120396 0.3048)
			(end 0.120396 0.2794)
			(stroke
				(width 0.1)
				(type default)
			)
			(layer "F.Fab")
		)
		(fp_line
			(start 0.12065 -0.3048)
			(end 0.67945 -0.3048)
			(stroke
				(width 0.1)
				(type default)
			)
			(layer "F.Fab")
		)
		(fp_line
			(start 0.12065 -0.2794)
			(end 0.12065 -0.3048)
			(stroke
				(width 0.1)
				(type default)
			)
			(layer "F.Fab")
		)
		(fp_line
			(start 0.67945 -0.3048)
			(end 0.67945 0.3048)
			(stroke
				(width 0.1)
				(type default)
			)
			(layer "F.Fab")
		)
		(fp_line
			(start 0.67945 0.3048)
			(end 0.120396 0.3048)
			(stroke
				(width 0.1)
				(type default)
			)
			(layer "F.Fab")
		)
		(pad "1" smd circle
			(at -0.40005 0)
			(size 0 0)
			(layers "F.Cu" "F.Mask" "F.Paste")
			(net "FM_DIS_PS_PWROK_DLY")
		)
		(pad "2" smd circle
			(at 0.40005 0)
			(size 0 0)
			(layers "F.Cu" "F.Mask" "F.Paste")
			(net "GND")
		)
	)
)
